(kicad_pcb
	(version 20260206)
	(generator "pcbnew")
	(generator_version "10.0")
	(general
		(thickness 1.6)
		(legacy_teardrops no)
	)
	(paper "A4")
	(title_block
		(title "01162023_DA0F0TEBIF0_F0T_Expander_BD_F_brd_V02_OCP.brd")
		(comment 1 "Grand Teton / footprints 2498-2505 of 9728")
	)
	(layers
		(0 "F.Cu" signal "TOP")
		(4 "In1.Cu" signal "GND")
		(6 "In2.Cu" signal "VCC")
		(8 "In3.Cu" signal "VCC1")
		(10 "In4.Cu" signal "GND1")
		(12 "In5.Cu" signal "IN1")
		(14 "In6.Cu" signal "GND2")
		(16 "In7.Cu" signal "IN2")
		(18 "In8.Cu" signal "GND3")
		(20 "In9.Cu" signal "IN3")
		(22 "In10.Cu" signal "GND4")
		(24 "In11.Cu" signal "IN4")
		(26 "In12.Cu" signal "GND5")
		(28 "In13.Cu" signal "IN5")
		(30 "In14.Cu" signal "GND6")
		(32 "In15.Cu" signal "IN6")
		(34 "In16.Cu" signal "GND7")
		(2 "B.Cu" signal "BOTTOM")
		(9 "F.Adhes" user "F.Adhesive")
		(11 "B.Adhes" user "B.Adhesive")
		(13 "F.Paste" user "Package Geometry/Pastemask Top")
		(15 "B.Paste" user "Package Geometry/Pastemask Bottom")
		(5 "F.SilkS" user "Ref Des/Silkscreen Top")
		(7 "B.SilkS" user "Ref Des/Silkscreen Bottom")
		(1 "F.Mask" user "Board Geometry/Soldermask Top")
		(3 "B.Mask" user "Board Geometry/Soldermask Bottom")
		(17 "Dwgs.User" user "User.Drawings")
		(19 "Cmts.User" user "User.Comments")
		(21 "Eco1.User" user "User.Eco1")
		(23 "Eco2.User" user "User.Eco2")
		(25 "Edge.Cuts" user "Board Geometry/Outline")
		(27 "Margin" user)
		(31 "F.CrtYd" user "Package Geometry/Place Bound Top")
		(29 "B.CrtYd" user "Package Geometry/Place Bound Bottom")
		(35 "F.Fab" user "Ref Des/Assembly Top")
		(33 "B.Fab" user "Ref Des/Assembly Bottom")
	)
	(footprint ""
		(layer "F.Cu")
		(at 274.089622 -356.244906 90)
		(property "Reference" "C2347"
			(at 0 0 90)
			(layer "F.SilkS")
			(hide yes)
			(effects
				(font
					(size 1.27 1.27)
				)
			)
		)
		(property "Value" ""
			(at 0 0 90)
			(layer "F.Fab")
			(effects
				(font
					(size 1.27 1.27)
				)
			)
		)
		(duplicate_pad_numbers_are_jumpers no)
		(fp_line
			(start 0.299974 -0.150114)
			(end 0.299974 0.150114)
			(stroke
				(width 0.1)
				(type default)
			)
			(layer "F.Fab")
		)
		(fp_line
			(start -0.299974 -0.150114)
			(end 0.299974 -0.150114)
			(stroke
				(width 0.1)
				(type default)
			)
			(layer "F.Fab")
		)
		(fp_line
			(start 0.299974 0.150114)
			(end -0.299974 0.150114)
			(stroke
				(width 0.1)
				(type default)
			)
			(layer "F.Fab")
		)
		(fp_line
			(start -0.299974 0.150114)
			(end -0.299974 -0.150114)
			(stroke
				(width 0.1)
				(type default)
			)
			(layer "F.Fab")
		)
		(pad "1" smd rect
			(at -0.2667 0 90)
			(size 0.3048 0.381)
			(layers "F.Cu" "F.Mask" "F.Paste")
			(net "P5E_PEX2_STN4_TX_DP<76>")
		)
		(pad "2" smd rect
			(at 0.2667 0 90)
			(size 0.3048 0.381)
			(layers "F.Cu" "F.Mask" "F.Paste")
			(net "P5E_PEX2_STN4_TX_C_DP<76>")
		)
	)
	(footprint ""
		(layer "F.Cu")
		(at 492.65967 -522.577822 90)
		(property "Reference" "VR_HS1"
			(at -0.3937 -0.588518 90)
			(unlocked yes)
			(layer "F.SilkS")
			(effects
				(font
					(size 0.254 0.127)
					(thickness 0.000001)
				)
				(justify left)
			)
		)
		(property "Value" ""
			(at 0 0 90)
			(layer "F.Fab")
			(effects
				(font
					(size 1.27 1.27)
				)
			)
		)
		(duplicate_pad_numbers_are_jumpers no)
		(pad "1" smd circle
			(at 0 0 90)
			(size 0.762 0.762)
			(layers "F.Cu" "F.Mask" "F.Paste")
			(net "Net_9197")
		)
	)
	(footprint ""
		(layer "F.Cu")
		(at 224.851976 -371.058186)
		(property "Reference" "PC11"
			(at 0 0 0)
			(layer "F.SilkS")
			(hide yes)
			(effects
				(font
					(size 1.27 1.27)
				)
			)
		)
		(property "Value" ""
			(at 0 0 0)
			(layer "F.Fab")
			(effects
				(font
					(size 1.27 1.27)
				)
			)
		)
		(duplicate_pad_numbers_are_jumpers no)
		(fp_line
			(start -0.7874 0.4064)
			(end -0.7874 -0.4064)
			(stroke
				(width 0.1524)
				(type default)
			)
			(layer "F.SilkS")
		)
		(fp_line
			(start 0.7874 -0.4064)
			(end 0.7874 0.4064)
			(stroke
				(width 0.1524)
				(type default)
			)
			(layer "F.SilkS")
		)
		(fp_line
			(start 0.7874 0.4064)
			(end -0.7874 0.4064)
			(stroke
				(width 0.1524)
				(type default)
			)
			(layer "F.SilkS")
		)
		(fp_line
			(start -0.67945 -0.305054)
			(end -0.12065 -0.305054)
			(stroke
				(width 0.1)
				(type default)
			)
			(layer "F.Fab")
		)
		(fp_line
			(start -0.67945 0.3048)
			(end -0.67945 -0.305054)
			(stroke
				(width 0.1)
				(type default)
			)
			(layer "F.Fab")
		)
		(fp_line
			(start -0.12065 -0.305054)
			(end -0.12065 -0.2794)
			(stroke
				(width 0.1)
				(type default)
			)
			(layer "F.Fab")
		)
		(fp_line
			(start -0.12065 -0.2794)
			(end 0.12065 -0.2794)
			(stroke
				(width 0.1)
				(type default)
			)
			(layer "F.Fab")
		)
		(fp_line
			(start -0.12065 0.2794)
			(end -0.12065 0.3048)
			(stroke
				(width 0.1)
				(type default)
			)
			(layer "F.Fab")
		)
		(fp_line
			(start -0.12065 0.3048)
			(end -0.67945 0.3048)
			(stroke
				(width 0.1)
				(type default)
			)
			(layer "F.Fab")
		)
		(fp_line
			(start 0.120396 0.2794)
			(end -0.12065 0.2794)
			(stroke
				(width 0.1)
				(type default)
			)
			(layer "F.Fab")
		)
		(fp_line
			(start 0.120396 0.3048)
			(end 0.120396 0.2794)
			(stroke
				(width 0.1)
				(type default)
			)
			(layer "F.Fab")
		)
		(fp_line
			(start 0.12065 -0.3048)
			(end 0.67945 -0.3048)
			(stroke
				(width 0.1)
				(type default)
			)
			(layer "F.Fab")
		)
		(fp_line
			(start 0.12065 -0.2794)
			(end 0.12065 -0.3048)
			(stroke
				(width 0.1)
				(type default)
			)
			(layer "F.Fab")
		)
		(fp_line
			(start 0.67945 -0.3048)
			(end 0.67945 0.3048)
			(stroke
				(width 0.1)
				(type default)
			)
			(layer "F.Fab")
		)
		(fp_line
			(start 0.67945 0.3048)
			(end 0.120396 0.3048)
			(stroke
				(width 0.1)
				(type default)
			)
			(layer "F.Fab")
		)
		(pad "1" smd circle
			(at -0.40005 0)
			(size 0 0)
			(layers "F.Cu" "F.Mask" "F.Paste")
			(net "HSC_ON")
		)
		(pad "2" smd circle
			(at 0.40005 0)
			(size 0 0)
			(layers "F.Cu" "F.Mask" "F.Paste")
			(net "AGND_HSC")
		)
	)
	(footprint ""
		(layer "F.Cu")
		(at 476.232728 -553.86859 90)
		(property "Reference" "HS_BP2"
			(at -0.5842 -1.31953 90)
			(unlocked yes)
			(layer "B.SilkS")
			(effects
				(font
					(size 0.7874 0.5842)
					(thickness 0.1524)
				)
				(justify left mirror)
			)
		)
		(property "Value" ""
			(at 0 0 90)
			(layer "F.Fab")
			(effects
				(font
					(size 1.27 1.27)
				)
			)
		)
		(duplicate_pad_numbers_are_jumpers no)
		(pad "1" thru_hole circle
			(at 0 0 90)
			(size 0.4572 0.4572)
			(drill 0.2032)
			(layers "*.Cu" "*.Mask")
			(remove_unused_layers no)
			(net "Net_9200")
			(clearance 0.127)
			(thermal_gap 0.127)
			(padstack
				(mode front_inner_back)
				(layer "Inner"
					(shape circle)
					(size 0.4572 0.4572)
					(clearance 0.127)
				)
				(layer "B.Cu"
					(shape circle)
					(size 0.508 0.508)
					(clearance 0.1016)
				)
			)
		)
	)
	(footprint ""
		(layer "F.Cu")
		(at 364.475776 -152.71115 -90)
		(property "Reference" "R754"
			(at 0 0 270)
			(layer "F.SilkS")
			(hide yes)
			(effects
				(font
					(size 1.27 1.27)
				)
			)
		)
		(property "Value" ""
			(at 0 0 270)
			(layer "F.Fab")
			(effects
				(font
					(size 1.27 1.27)
				)
			)
		)
		(duplicate_pad_numbers_are_jumpers no)
		(fp_line
			(start -0.7874 0.4064)
			(end -0.7874 -0.4064)
			(stroke
				(width 0.1524)
				(type default)
			)
			(layer "F.SilkS")
		)
		(fp_line
			(start 0.7874 0.4064)
			(end -0.7874 0.4064)
			(stroke
				(width 0.1524)
				(type default)
			)
			(layer "F.SilkS")
		)
		(fp_line
			(start -0.7874 -0.4064)
			(end 0.7874 -0.4064)
			(stroke
				(width 0.1524)
				(type default)
			)
			(layer "F.SilkS")
		)
		(fp_line
			(start 0.7874 -0.4064)
			(end 0.7874 0.4064)
			(stroke
				(width 0.1524)
				(type default)
			)
			(layer "F.SilkS")
		)
		(fp_line
			(start -0.67945 0.3048)
			(end -0.67945 -0.305054)
			(stroke
				(width 0.1)
				(type default)
			)
			(layer "F.Fab")
		)
		(fp_line
			(start -0.12065 0.3048)
			(end -0.67945 0.3048)
			(stroke
				(width 0.1)
				(type default)
			)
			(layer "F.Fab")
		)
		(fp_line
			(start 0.120396 0.3048)
			(end 0.120396 0.2794)
			(stroke
				(width 0.1)
				(type default)
			)
			(layer "F.Fab")
		)
		(fp_line
			(start 0.67945 0.3048)
			(end 0.120396 0.3048)
			(stroke
				(width 0.1)
				(type default)
			)
			(layer "F.Fab")
		)
		(fp_line
			(start -0.12065 0.2794)
			(end -0.12065 0.3048)
			(stroke
				(width 0.1)
				(type default)
			)
			(layer "F.Fab")
		)
		(fp_line
			(start 0.120396 0.2794)
			(end -0.12065 0.2794)
			(stroke
				(width 0.1)
				(type default)
			)
			(layer "F.Fab")
		)
		(fp_line
			(start -0.12065 -0.2794)
			(end 0.12065 -0.2794)
			(stroke
				(width 0.1)
				(type default)
			)
			(layer "F.Fab")
		)
		(fp_line
			(start 0.12065 -0.2794)
			(end 0.12065 -0.3048)
			(stroke
				(width 0.1)
				(type default)
			)
			(layer "F.Fab")
		)
		(fp_line
			(start 0.12065 -0.3048)
			(end 0.67945 -0.3048)
			(stroke
				(width 0.1)
				(type default)
			)
			(layer "F.Fab")
		)
		(fp_line
			(start 0.67945 -0.3048)
			(end 0.67945 0.3048)
			(stroke
				(width 0.1)
				(type default)
			)
			(layer "F.Fab")
		)
		(fp_line
			(start -0.67945 -0.305054)
			(end -0.12065 -0.305054)
			(stroke
				(width 0.1)
				(type default)
			)
			(layer "F.Fab")
		)
		(fp_line
			(start -0.12065 -0.305054)
			(end -0.12065 -0.2794)
			(stroke
				(width 0.1)
				(type default)
			)
			(layer "F.Fab")
		)
		(pad "1" smd circle
			(at -0.40005 0 270)
			(size 0 0)
			(layers "F.Cu" "F.Mask" "F.Paste")
			(net "SMB_BIC_I2C6_MUX_NIC_ADC_R_SDA")
		)
		(pad "2" smd circle
			(at 0.40005 0 270)
			(size 0 0)
			(layers "F.Cu" "F.Mask" "F.Paste")
			(net "SMB_NIC6_ADC_SDA")
		)
	)
	(footprint ""
		(layer "F.Cu")
		(at 338.074 -142.875 180)
		(property "Reference" "R4836"
			(at 0 0 180)
			(layer "F.SilkS")
			(hide yes)
			(effects
				(font
					(size 1.27 1.27)
				)
			)
		)
		(property "Value" ""
			(at 0 0 180)
			(layer "F.Fab")
			(effects
				(font
					(size 1.27 1.27)
				)
			)
		)
		(duplicate_pad_numbers_are_jumpers no)
		(fp_line
			(start 0.7874 0.4064)
			(end -0.7874 0.4064)
			(stroke
				(width 0.1524)
				(type default)
			)
			(layer "F.SilkS")
		)
		(fp_line
			(start 0.7874 -0.4064)
			(end 0.7874 0.4064)
			(stroke
				(width 0.1524)
				(type default)
			)
			(layer "F.SilkS")
		)
		(fp_line
			(start -0.7874 0.4064)
			(end -0.7874 -0.4064)
			(stroke
				(width 0.1524)
				(type default)
			)
			(layer "F.SilkS")
		)
		(fp_line
			(start -0.7874 -0.4064)
			(end 0.7874 -0.4064)
			(stroke
				(width 0.1524)
				(type default)
			)
			(layer "F.SilkS")
		)
		(fp_line
			(start 0.67945 0.3048)
			(end 0.120396 0.3048)
			(stroke
				(width 0.1)
				(type default)
			)
			(layer "F.Fab")
		)
		(fp_line
			(start 0.67945 -0.3048)
			(end 0.67945 0.3048)
			(stroke
				(width 0.1)
				(type default)
			)
			(layer "F.Fab")
		)
		(fp_line
			(start 0.12065 -0.2794)
			(end 0.12065 -0.3048)
			(stroke
				(width 0.1)
				(type default)
			)
			(layer "F.Fab")
		)
		(fp_line
			(start 0.12065 -0.3048)
			(end 0.67945 -0.3048)
			(stroke
				(width 0.1)
				(type default)
			)
			(layer "F.Fab")
		)
		(fp_line
			(start 0.120396 0.3048)
			(end 0.120396 0.2794)
			(stroke
				(width 0.1)
				(type default)
			)
			(layer "F.Fab")
		)
		(fp_line
			(start 0.120396 0.2794)
			(end -0.12065 0.2794)
			(stroke
				(width 0.1)
				(type default)
			)
			(layer "F.Fab")
		)
		(fp_line
			(start -0.12065 0.3048)
			(end -0.67945 0.3048)
			(stroke
				(width 0.1)
				(type default)
			)
			(layer "F.Fab")
		)
		(fp_line
			(start -0.12065 0.2794)
			(end -0.12065 0.3048)
			(stroke
				(width 0.1)
				(type default)
			)
			(layer "F.Fab")
		)
		(fp_line
			(start -0.12065 -0.2794)
			(end 0.12065 -0.2794)
			(stroke
				(width 0.1)
				(type default)
			)
			(layer "F.Fab")
		)
		(fp_line
			(start -0.12065 -0.305054)
			(end -0.12065 -0.2794)
			(stroke
				(width 0.1)
				(type default)
			)
			(layer "F.Fab")
		)
		(fp_line
			(start -0.67945 0.3048)
			(end -0.67945 -0.305054)
			(stroke
				(width 0.1)
				(type default)
			)
			(layer "F.Fab")
		)
		(fp_line
			(start -0.67945 -0.305054)
			(end -0.12065 -0.305054)
			(stroke
				(width 0.1)
				(type default)
			)
			(layer "F.Fab")
		)
		(pad "1" smd circle
			(at -0.40005 0 180)
			(size 0 0)
			(layers "F.Cu" "F.Mask" "F.Paste")
			(net "SSD15_PEX_PWR_EN")
		)
		(pad "2" smd circle
			(at 0.40005 0 180)
			(size 0 0)
			(layers "F.Cu" "F.Mask" "F.Paste")
			(net "SSD15_PEX_PWR_EN_R")
		)
	)
	(footprint ""
		(layer "F.Cu")
		(at 204.591158 -79.595472)
		(property "Reference" "R4335"
			(at 0 0 0)
			(layer "F.SilkS")
			(hide yes)
			(effects
				(font
					(size 1.27 1.27)
				)
			)
		)
		(property "Value" ""
			(at 0 0 0)
			(layer "F.Fab")
			(effects
				(font
					(size 1.27 1.27)
				)
			)
		)
		(duplicate_pad_numbers_are_jumpers no)
		(fp_line
			(start -0.7874 -0.4064)
			(end 0.7874 -0.4064)
			(stroke
				(width 0.1524)
				(type default)
			)
			(layer "F.SilkS")
		)
		(fp_line
			(start -0.7874 0.4064)
			(end -0.7874 -0.4064)
			(stroke
				(width 0.1524)
				(type default)
			)
			(layer "F.SilkS")
		)
		(fp_line
			(start 0.7874 -0.4064)
			(end 0.7874 0.4064)
			(stroke
				(width 0.1524)
				(type default)
			)
			(layer "F.SilkS")
		)
		(fp_line
			(start 0.7874 0.4064)
			(end -0.7874 0.4064)
			(stroke
				(width 0.1524)
				(type default)
			)
			(layer "F.SilkS")
		)
		(fp_line
			(start -0.67945 -0.305054)
			(end -0.12065 -0.305054)
			(stroke
				(width 0.1)
				(type default)
			)
			(layer "F.Fab")
		)
		(fp_line
			(start -0.67945 0.3048)
			(end -0.67945 -0.305054)
			(stroke
				(width 0.1)
				(type default)
			)
			(layer "F.Fab")
		)
		(fp_line
			(start -0.12065 -0.305054)
			(end -0.12065 -0.2794)
			(stroke
				(width 0.1)
				(type default)
			)
			(layer "F.Fab")
		)
		(fp_line
			(start -0.12065 -0.2794)
			(end 0.12065 -0.2794)
			(stroke
				(width 0.1)
				(type default)
			)
			(layer "F.Fab")
		)
		(fp_line
			(start -0.12065 0.2794)
			(end -0.12065 0.3048)
			(stroke
				(width 0.1)
				(type default)
			)
			(layer "F.Fab")
		)
		(fp_line
			(start -0.12065 0.3048)
			(end -0.67945 0.3048)
			(stroke
				(width 0.1)
				(type default)
			)
			(layer "F.Fab")
		)
		(fp_line
			(start 0.120396 0.2794)
			(end -0.12065 0.2794)
			(stroke
				(width 0.1)
				(type default)
			)
			(layer "F.Fab")
		)
		(fp_line
			(start 0.120396 0.3048)
			(end 0.120396 0.2794)
			(stroke
				(width 0.1)
				(type default)
			)
			(layer "F.Fab")
		)
		(fp_line
			(start 0.12065 -0.3048)
			(end 0.67945 -0.3048)
			(stroke
				(width 0.1)
				(type default)
			)
			(layer "F.Fab")
		)
		(fp_line
			(start 0.12065 -0.2794)
			(end 0.12065 -0.3048)
			(stroke
				(width 0.1)
				(type default)
			)
			(layer "F.Fab")
		)
		(fp_line
			(start 0.67945 -0.3048)
			(end 0.67945 0.3048)
			(stroke
				(width 0.1)
				(type default)
			)
			(layer "F.Fab")
		)
		(fp_line
			(start 0.67945 0.3048)
			(end 0.120396 0.3048)
			(stroke
				(width 0.1)
				(type default)
			)
			(layer "F.Fab")
		)
		(pad "1" smd circle
			(at -0.40005 0)
			(size 0 0)
			(layers "F.Cu" "F.Mask" "F.Paste")
			(net "P3V3_AUX")
		)
		(pad "2" smd circle
			(at 0.40005 0)
			(size 0 0)
			(layers "F.Cu" "F.Mask" "F.Paste")
			(net "SSD5_LED_R")
		)
	)
	(footprint ""
		(layer "F.Cu")
		(at 8.110474 -68.732146 180)
		(property "Reference" "R5872"
			(at 0 0 180)
			(layer "F.SilkS")
			(hide yes)
			(effects
				(font
					(size 1.27 1.27)
				)
			)
		)
		(property "Value" ""
			(at 0 0 180)
			(layer "F.Fab")
			(effects
				(font
					(size 1.27 1.27)
				)
			)
		)
		(duplicate_pad_numbers_are_jumpers no)
		(fp_line
			(start 0.7874 0.4064)
			(end -0.7874 0.4064)
			(stroke
				(width 0.1524)
				(type default)
			)
			(layer "F.SilkS")
		)
		(fp_line
			(start 0.7874 -0.4064)
			(end 0.7874 0.4064)
			(stroke
				(width 0.1524)
				(type default)
			)
			(layer "F.SilkS")
		)
		(fp_line
			(start -0.7874 0.4064)
			(end -0.7874 -0.4064)
			(stroke
				(width 0.1524)
				(type default)
			)
			(layer "F.SilkS")
		)
		(fp_line
			(start -0.7874 -0.4064)
			(end 0.7874 -0.4064)
			(stroke
				(width 0.1524)
				(type default)
			)
			(layer "F.SilkS")
		)
		(fp_line
			(start 0.67945 0.3048)
			(end 0.120396 0.3048)
			(stroke
				(width 0.1)
				(type default)
			)
			(layer "F.Fab")
		)
		(fp_line
			(start 0.67945 -0.3048)
			(end 0.67945 0.3048)
			(stroke
				(width 0.1)
				(type default)
			)
			(layer "F.Fab")
		)
		(fp_line
			(start 0.12065 -0.2794)
			(end 0.12065 -0.3048)
			(stroke
				(width 0.1)
				(type default)
			)
			(layer "F.Fab")
		)
		(fp_line
			(start 0.12065 -0.3048)
			(end 0.67945 -0.3048)
			(stroke
				(width 0.1)
				(type default)
			)
			(layer "F.Fab")
		)
		(fp_line
			(start 0.120396 0.3048)
			(end 0.120396 0.2794)
			(stroke
				(width 0.1)
				(type default)
			)
			(layer "F.Fab")
		)
		(fp_line
			(start 0.120396 0.2794)
			(end -0.12065 0.2794)
			(stroke
				(width 0.1)
				(type default)
			)
			(layer "F.Fab")
		)
		(fp_line
			(start -0.12065 0.3048)
			(end -0.67945 0.3048)
			(stroke
				(width 0.1)
				(type default)
			)
			(layer "F.Fab")
		)
		(fp_line
			(start -0.12065 0.2794)
			(end -0.12065 0.3048)
			(stroke
				(width 0.1)
				(type default)
			)
			(layer "F.Fab")
		)
		(fp_line
			(start -0.12065 -0.2794)
			(end 0.12065 -0.2794)
			(stroke
				(width 0.1)
				(type default)
			)
			(layer "F.Fab")
		)
		(fp_line
			(start -0.12065 -0.305054)
			(end -0.12065 -0.2794)
			(stroke
				(width 0.1)
				(type default)
			)
			(layer "F.Fab")
		)
		(fp_line
			(start -0.67945 0.3048)
			(end -0.67945 -0.305054)
			(stroke
				(width 0.1)
				(type default)
			)
			(layer "F.Fab")
		)
		(fp_line
			(start -0.67945 -0.305054)
			(end -0.12065 -0.305054)
			(stroke
				(width 0.1)
				(type default)
			)
			(layer "F.Fab")
		)
		(pad "1" smd circle
			(at -0.40005 0 180)
			(size 0 0)
			(layers "F.Cu" "F.Mask" "F.Paste")
			(net "P5V_AUX")
		)
		(pad "2" smd circle
			(at 0.40005 0 180)
			(size 0 0)
			(layers "F.Cu" "F.Mask" "F.Paste")
			(net "P3V3_SSD0_PG_G2")
		)
	)
)
